FILE_TYPE = MULTI_PHYS_TABLE;

PART 'SCONN288_ADR50017P130CC'

{========================================================================================}
:VALUE                      | PART_TYPE | MATERIAL | PART_NUMBER    = STANDARD | LIFECYCLE     | PART_NUMBER   | JEDEC_TYPE       | DESCRIPTION                                | MANUFTR | MANUF_PN          | RD_CMPLS_LVL | CMPLS_LVL | CLASS | DIP_SMD | FROM_PJ    | DATA                      | FP_ECN                | EE_CHECK_LIST | CREATOR | CREATEDAY  | PSL | STATUS | ESD_CDM | ESD_HBM | ESD_MM | MSD | PIN_LENGTH_LONG_PIN | PIN_LENGTH_SHORT_PIN ;
{========================================================================================}
 'SCONN288_ADR50017-P130CC' | 'SMLF'    | 'IO'     | 'DFHST8FS461'(!) = ''       | ''               | 'DFHST8FS461' |'DDR288S_1-1VXB'| 'CONN SMD HS DDR5 288P 2R FS(P0.85,H21.3)' | 'LTS'   | 'ADR50017-P130CC' | 'EP(V1)'     | ''        | 'IO'  | ''      | 'F0C-IVES' | 'LTS_ADR50017-P130CC.pdf' | 'ADR50017-P130CC.msg' | ''            | ''      | '20210723' | ''  | ''     | ''      | ''      | ''     | ''  | '81 MILS'           | '81 MILS'           
 'SCONN288_ADR50017-P130CC' | 'SMLF'    | 'EMPTY'  | 'DFHST8FS461'(!) = ''       | ''               | 'DFHST8FS461' |'DDR288S_1-1VXB'| 'CONN SMD HS DDR5 288P 2R FS(P0.85,H21.3)' | 'LTS'   | 'ADR50017-P130CC' | 'EP(V1)'     | ''        | 'IO'  | ''      | 'F0C-IVES' | 'LTS_ADR50017-P130CC.pdf' | 'ADR50017-P130CC.msg' | ''            | ''      | '20210723' | ''  | ''     | ''      | ''      | ''     | ''  | '81 MILS'           | '81 MILS'           

END_PART

END.

